(kicad_pcb
	(version 20260206)
	(generator "pcbnew")
	(generator_version "10.0")
	(general
		(thickness 1.6)
		(legacy_teardrops no)
	)
	(paper "A4")
	(title_block
		(title "baseboard — 13948-1b.1110WZS1818.brd")
		(comment 1 "Honey Badger (Wiwynn) / footprints 744-750 of 2523")
	)
	(layers
		(0 "F.Cu" signal "TOP")
		(4 "In1.Cu" signal "L2GND")
		(6 "In2.Cu" signal "L3")
		(8 "In3.Cu" signal "L4VCC")
		(10 "In4.Cu" signal "L5VCC")
		(12 "In5.Cu" signal "L6")
		(14 "In6.Cu" signal "L7GND")
		(2 "B.Cu" signal "BOTTOM")
		(9 "F.Adhes" user "F.Adhesive")
		(11 "B.Adhes" user "B.Adhesive")
		(13 "F.Paste" user "Package Geometry/Pastemask Top")
		(15 "B.Paste" user "Package Geometry/Pastemask Bottom")
		(5 "F.SilkS" user "Ref Des/Silkscreen Top")
		(7 "B.SilkS" user "Ref Des/Silkscreen Bottom")
		(1 "F.Mask" user "Board Geometry/Soldermask Top")
		(3 "B.Mask" user "Board Geometry/Soldermask Bottom")
		(17 "Dwgs.User" user "User.Drawings")
		(19 "Cmts.User" user "User.Comments")
		(21 "Eco1.User" user "User.Eco1")
		(23 "Eco2.User" user "User.Eco2")
		(25 "Edge.Cuts" user "Board Geometry/Outline")
		(27 "Margin" user)
		(31 "F.CrtYd" user "Package Geometry/Place Bound Top")
		(29 "B.CrtYd" user "Package Geometry/Place Bound Bottom")
		(35 "F.Fab" user "Ref Des/Assembly Top")
		(33 "B.Fab" user "Ref Des/Assembly Bottom")
	)
	(footprint ""
		(layer "F.Cu")
		(at 83.420966 -91.44 180)
		(property "Reference" "SC1198"
			(at 0 0 180)
			(layer "F.SilkS")
			(hide yes)
			(effects
				(font
					(size 1.27 1.27)
				)
			)
		)
		(property "Value" "SC22U6D3V5MX-2GP"
			(at -0.0762 -6.1214 180)
			(unlocked yes)
			(layer "F.Fab")
			(hide yes)
			(effects
				(font
					(size 1.016 1.016)
					(thickness 0.1524)
				)
			)
		)
		(property "Device Type" "C805H58"
			(at -0.0762 -8.1534 180)
			(unlocked yes)
			(layer "F.Fab")
			(hide yes)
			(effects
				(font
					(size 1.016 1.016)
					(thickness 0.1524)
				)
			)
		)
		(duplicate_pad_numbers_are_jumpers no)
		(fp_line
			(start 0.635 0)
			(end -0.635 0)
			(stroke
				(width 0.508)
				(type default)
			)
			(layer "F.SilkS")
		)
		(fp_rect
			(start -0.9652 1.778)
			(end 0.9652 -1.778)
			(stroke
				(width 0)
				(type default)
			)
			(fill no)
			(layer "F.CrtYd")
		)
		(fp_poly
			(pts
				(xy -0.9652 -1.778) (xy 0.9652 -1.778) (xy 0.9652 1.778) (xy -0.9652 1.778)
			)
			(stroke
				(width 0)
				(type default)
			)
			(fill no)
			(layer "F.Fab")
		)
		(pad "1" smd rect
			(at 0 -0.9652 180)
			(size 1.397 1.143)
			(layers "F.Cu" "F.Mask" "F.Paste")
			(net "SYSPLL_VDDA09")
		)
		(pad "2" smd rect
			(at 0 0.9652 180)
			(size 1.397 1.143)
			(layers "F.Cu" "F.Mask" "F.Paste")
			(net "GND")
		)
	)
	(footprint ""
		(layer "F.Cu")
		(at 320.675 -7.62 90)
		(property "Reference" "R433"
			(at 0 0 90)
			(layer "F.SilkS")
			(hide yes)
			(effects
				(font
					(size 1.27 1.27)
				)
			)
		)
		(property "Value" "1KR2F-3-GP"
			(at 0.064008 -3.993896 90)
			(unlocked yes)
			(layer "F.Fab")
			(hide yes)
			(effects
				(font
					(size 1.016 1.016)
					(thickness 0.1524)
				)
			)
		)
		(property "Device Type" "R402H16"
			(at 0.064008 -5.517896 90)
			(unlocked yes)
			(layer "F.Fab")
			(hide yes)
			(effects
				(font
					(size 1.016 1.016)
					(thickness 0.1524)
				)
			)
		)
		(duplicate_pad_numbers_are_jumpers no)
		(fp_line
			(start 0.508 -0.9398)
			(end -0.508 -0.9398)
			(stroke
				(width 0.1524)
				(type default)
			)
			(layer "F.SilkS")
		)
		(fp_line
			(start -0.508 -0.9398)
			(end -0.508 0.9398)
			(stroke
				(width 0.1524)
				(type default)
			)
			(layer "F.SilkS")
		)
		(fp_rect
			(start -0.508 0.9398)
			(end 0.508 -0.9398)
			(stroke
				(width 0)
				(type default)
			)
			(fill no)
			(layer "F.CrtYd")
		)
		(fp_rect
			(start -0.508 0.9398)
			(end 0.508 -0.9398)
			(stroke
				(width 0)
				(type default)
			)
			(fill no)
			(layer "F.Fab")
		)
		(pad "1" smd custom
			(at 0 -0.4445 90)
			(size 0.1397 0.1397)
			(layers "F.Cu" "F.Mask" "F.Paste")
			(net "P3V3_STBY")
			(options
				(clearance outline)
				(anchor circle)
			)
			(primitives
				(gr_poly
					(pts
						(arc
							(start -0.1778 -0.2794)
							(mid -0.249642 -0.249642)
							(end -0.2794 -0.1778)
						)
						(arc
							(start -0.2794 0.1778)
							(mid -0.249642 0.249642)
							(end -0.1778 0.2794)
						)
						(arc
							(start 0.1778 0.2794)
							(mid 0.249642 0.249642)
							(end 0.2794 0.1778)
						)
						(arc
							(start 0.2794 -0.1778)
							(mid 0.249642 -0.249642)
							(end 0.1778 -0.2794)
						)
					)
					(width 0)
					(fill yes)
				)
			)
		)
		(pad "2" smd custom
			(at 0 0.4445 90)
			(size 0.1397 0.1397)
			(layers "F.Cu" "F.Mask" "F.Paste")
			(net "DEBUG_LED_SW_H")
			(options
				(clearance outline)
				(anchor circle)
			)
			(primitives
				(gr_poly
					(pts
						(arc
							(start -0.1778 -0.2794)
							(mid -0.249642 -0.249642)
							(end -0.2794 -0.1778)
						)
						(arc
							(start -0.2794 0.1778)
							(mid -0.249642 0.249642)
							(end -0.1778 0.2794)
						)
						(arc
							(start 0.1778 0.2794)
							(mid 0.249642 0.249642)
							(end 0.2794 0.1778)
						)
						(arc
							(start 0.2794 -0.1778)
							(mid 0.249642 -0.249642)
							(end 0.1778 -0.2794)
						)
					)
					(width 0)
					(fill yes)
				)
			)
		)
	)
	(footprint ""
		(layer "F.Cu")
		(at 340.106 -29.464 180)
		(property "Reference" "Q20"
			(at 0 0 180)
			(layer "F.SilkS")
			(hide yes)
			(effects
				(font
					(size 1.27 1.27)
				)
			)
		)
		(property "Value" "2N7002A-7-GP"
			(at 0.127 -8.9662 180)
			(unlocked yes)
			(layer "F.Fab")
			(hide yes)
			(effects
				(font
					(size 1.016 1.016)
					(thickness 0.1524)
				)
			)
		)
		(property "Device Type" "SOT23DGS2D4H48"
			(at 0.127 -10.4902 180)
			(unlocked yes)
			(layer "F.Fab")
			(hide yes)
			(effects
				(font
					(size 1.016 1.016)
					(thickness 0.1524)
				)
			)
		)
		(duplicate_pad_numbers_are_jumpers no)
		(fp_line
			(start 1.651 1.778)
			(end 1.651 -1.778)
			(stroke
				(width 0.1524)
				(type default)
			)
			(layer "F.SilkS")
		)
		(fp_line
			(start 1.651 -1.778)
			(end -1.651 -1.778)
			(stroke
				(width 0.1524)
				(type default)
			)
			(layer "F.SilkS")
		)
		(fp_line
			(start -1.651 1.778)
			(end 1.651 1.778)
			(stroke
				(width 0.1524)
				(type default)
			)
			(layer "F.SilkS")
		)
		(fp_line
			(start -1.651 -1.778)
			(end -1.651 1.778)
			(stroke
				(width 0.1524)
				(type default)
			)
			(layer "F.SilkS")
		)
		(fp_poly
			(pts
				(xy -1.778 1.8796) (xy -1.778 -1.8796) (xy 1.778 -1.8796) (xy 1.778 1.8796)
			)
			(stroke
				(width 0)
				(type default)
			)
			(fill no)
			(layer "F.CrtYd")
		)
		(fp_poly
			(pts
				(xy -1.778 1.8796) (xy -1.778 -1.8796) (xy 1.778 -1.8796) (xy 1.778 1.8796)
			)
			(stroke
				(width 0)
				(type default)
			)
			(fill no)
			(layer "F.Fab")
		)
		(pad "D" smd custom
			(at 0 -0.9525 180)
			(size 0.1905 0.1905)
			(layers "F.Cu" "F.Mask" "F.Paste")
			(net "DEBUG CONSOLE_LED_1")
			(options
				(clearance outline)
				(anchor circle)
			)
			(primitives
				(gr_poly
					(pts
						(arc
							(start -0.1778 0.5715)
							(mid -0.321484 0.511984)
							(end -0.381 0.3683)
						)
						(arc
							(start -0.381 -0.3683)
							(mid -0.321484 -0.511984)
							(end -0.1778 -0.5715)
						)
						(arc
							(start 0.1778 -0.5715)
							(mid 0.321484 -0.511984)
							(end 0.381 -0.3683)
						)
						(arc
							(start 0.381 0.3683)
							(mid 0.321484 0.511984)
							(end 0.1778 0.5715)
						)
					)
					(width 0)
					(fill yes)
				)
			)
		)
		(pad "G" smd custom
			(at -0.98425 0.9525 180)
			(size 0.1905 0.1905)
			(layers "F.Cu" "F.Mask" "F.Paste")
			(net "BMC_CONSOLE_LED1_R")
			(options
				(clearance outline)
				(anchor circle)
			)
			(primitives
				(gr_poly
					(pts
						(arc
							(start -0.1778 0.5715)
							(mid -0.321484 0.511984)
							(end -0.381 0.3683)
						)
						(arc
							(start -0.381 -0.3683)
							(mid -0.321484 -0.511984)
							(end -0.1778 -0.5715)
						)
						(arc
							(start 0.1778 -0.5715)
							(mid 0.321484 -0.511984)
							(end 0.381 -0.3683)
						)
						(arc
							(start 0.381 0.3683)
							(mid 0.321484 0.511984)
							(end 0.1778 0.5715)
						)
					)
					(width 0)
					(fill yes)
				)
			)
		)
		(pad "S" smd custom
			(at 0.98425 0.9525 180)
			(size 0.1905 0.1905)
			(layers "F.Cu" "F.Mask" "F.Paste")
			(net "GND")
			(options
				(clearance outline)
				(anchor circle)
			)
			(primitives
				(gr_poly
					(pts
						(arc
							(start -0.1778 0.5715)
							(mid -0.321484 0.511984)
							(end -0.381 0.3683)
						)
						(arc
							(start -0.381 -0.3683)
							(mid -0.321484 -0.511984)
							(end -0.1778 -0.5715)
						)
						(arc
							(start 0.1778 -0.5715)
							(mid 0.321484 -0.511984)
							(end 0.381 -0.3683)
						)
						(arc
							(start 0.381 0.3683)
							(mid 0.321484 0.511984)
							(end 0.1778 0.5715)
						)
					)
					(width 0)
					(fill yes)
				)
			)
		)
	)
	(footprint ""
		(layer "F.Cu")
		(at 260.731 -36.703 180)
		(property "Reference" "PR47"
			(at 0 0 180)
			(layer "F.SilkS")
			(hide yes)
			(effects
				(font
					(size 1.27 1.27)
				)
			)
		)
		(property "Value" "10R3F-GP"
			(at -0.0254 -2.5146 180)
			(unlocked yes)
			(layer "F.Fab")
			(hide yes)
			(effects
				(font
					(size 1.016 1.016)
					(thickness 0.1524)
				)
			)
		)
		(property "Device Type" "R603H22"
			(at -0.0254 -4.0386 180)
			(unlocked yes)
			(layer "F.Fab")
			(hide yes)
			(effects
				(font
					(size 1.016 1.016)
					(thickness 0.1524)
				)
			)
		)
		(duplicate_pad_numbers_are_jumpers no)
		(fp_line
			(start 0.2032 0)
			(end 0.4826 0)
			(stroke
				(width 0.2032)
				(type default)
			)
			(layer "F.SilkS")
		)
		(fp_line
			(start -0.4826 0)
			(end -0.2032 0)
			(stroke
				(width 0.2032)
				(type default)
			)
			(layer "F.SilkS")
		)
		(fp_rect
			(start -0.5842 1.3335)
			(end 0.5842 -1.3335)
			(stroke
				(width 0)
				(type default)
			)
			(fill no)
			(layer "F.CrtYd")
		)
		(fp_rect
			(start -0.5842 1.3335)
			(end 0.5842 -1.3335)
			(stroke
				(width 0)
				(type default)
			)
			(fill no)
			(layer "F.Fab")
		)
		(pad "1" smd custom
			(at 0 -0.762 180)
			(size 0.2159 0.2159)
			(layers "F.Cu" "F.Mask" "F.Paste")
			(net "P1V8_STBY")
			(options
				(clearance outline)
				(anchor circle)
			)
			(primitives
				(gr_poly
					(pts
						(arc
							(start -0.3302 -0.4318)
							(mid -0.402042 -0.402042)
							(end -0.4318 -0.3302)
						)
						(arc
							(start -0.4318 0.3302)
							(mid -0.402042 0.402042)
							(end -0.3302 0.4318)
						)
						(arc
							(start 0.3302 0.4318)
							(mid 0.402042 0.402042)
							(end 0.4318 0.3302)
						)
						(arc
							(start 0.4318 -0.3302)
							(mid 0.402042 -0.402042)
							(end 0.3302 -0.4318)
						)
					)
					(width 0)
					(fill yes)
				)
			)
		)
		(pad "2" smd custom
			(at 0 0.762 180)
			(size 0.2159 0.2159)
			(layers "F.Cu" "F.Mask" "F.Paste")
			(net "P1V8_STBY_VFB_R")
			(options
				(clearance outline)
				(anchor circle)
			)
			(primitives
				(gr_poly
					(pts
						(arc
							(start -0.3302 -0.4318)
							(mid -0.402042 -0.402042)
							(end -0.4318 -0.3302)
						)
						(arc
							(start -0.4318 0.3302)
							(mid -0.402042 0.402042)
							(end -0.3302 0.4318)
						)
						(arc
							(start 0.3302 0.4318)
							(mid 0.402042 0.402042)
							(end 0.4318 0.3302)
						)
						(arc
							(start 0.4318 -0.3302)
							(mid 0.402042 -0.402042)
							(end 0.3302 -0.4318)
						)
					)
					(width 0)
					(fill yes)
				)
			)
		)
	)
	(footprint ""
		(layer "F.Cu")
		(at 55.88 -211.074)
		(property "Reference" "PR9006"
			(at 0 0 0)
			(layer "F.SilkS")
			(hide yes)
			(effects
				(font
					(size 1.27 1.27)
				)
			)
		)
		(property "Value" "0R2J-2-GP"
			(at 0.064008 -3.993896 0)
			(unlocked yes)
			(layer "F.Fab")
			(hide yes)
			(effects
				(font
					(size 1.016 1.016)
					(thickness 0.1524)
				)
			)
		)
		(property "Device Type" "R402H16"
			(at 0.064008 -5.517896 0)
			(unlocked yes)
			(layer "F.Fab")
			(hide yes)
			(effects
				(font
					(size 1.016 1.016)
					(thickness 0.1524)
				)
			)
		)
		(duplicate_pad_numbers_are_jumpers no)
		(fp_line
			(start -0.508 -0.9398)
			(end -0.508 0.9398)
			(stroke
				(width 0.1524)
				(type default)
			)
			(layer "F.SilkS")
		)
		(fp_line
			(start 0.508 -0.9398)
			(end -0.508 -0.9398)
			(stroke
				(width 0.1524)
				(type default)
			)
			(layer "F.SilkS")
		)
		(fp_rect
			(start -0.508 0.9398)
			(end 0.508 -0.9398)
			(stroke
				(width 0)
				(type default)
			)
			(fill no)
			(layer "F.CrtYd")
		)
		(fp_rect
			(start -0.508 0.9398)
			(end 0.508 -0.9398)
			(stroke
				(width 0)
				(type default)
			)
			(fill no)
			(layer "F.Fab")
		)
		(pad "1" smd custom
			(at 0 -0.4445)
			(size 0.1397 0.1397)
			(layers "F.Cu" "F.Mask" "F.Paste")
			(net "HSW_SDA_2")
			(options
				(clearance outline)
				(anchor circle)
			)
			(primitives
				(gr_poly
					(pts
						(arc
							(start -0.1778 -0.2794)
							(mid -0.249642 -0.249642)
							(end -0.2794 -0.1778)
						)
						(arc
							(start -0.2794 0.1778)
							(mid -0.249642 0.249642)
							(end -0.1778 0.2794)
						)
						(arc
							(start 0.1778 0.2794)
							(mid 0.249642 0.249642)
							(end 0.2794 0.1778)
						)
						(arc
							(start 0.2794 -0.1778)
							(mid 0.249642 -0.249642)
							(end 0.1778 -0.2794)
						)
					)
					(width 0)
					(fill yes)
				)
			)
		)
		(pad "2" smd custom
			(at 0 0.4445)
			(size 0.1397 0.1397)
			(layers "F.Cu" "F.Mask" "F.Paste")
			(net "BMC_I2C_A_SDA")
			(options
				(clearance outline)
				(anchor circle)
			)
			(primitives
				(gr_poly
					(pts
						(arc
							(start -0.1778 -0.2794)
							(mid -0.249642 -0.249642)
							(end -0.2794 -0.1778)
						)
						(arc
							(start -0.2794 0.1778)
							(mid -0.249642 0.249642)
							(end -0.1778 0.2794)
						)
						(arc
							(start 0.1778 0.2794)
							(mid 0.249642 0.249642)
							(end 0.2794 0.1778)
						)
						(arc
							(start 0.2794 -0.1778)
							(mid 0.249642 -0.249642)
							(end 0.1778 -0.2794)
						)
					)
					(width 0)
					(fill yes)
				)
			)
		)
	)
	(footprint ""
		(layer "F.Cu")
		(at 172.339 -102.743)
		(property "Reference" "PL9"
			(at 0 0 0)
			(layer "F.SilkS")
			(hide yes)
			(effects
				(font
					(size 1.27 1.27)
				)
			)
		)
		(property "Value" "IND-300NH-8-GP"
			(at -5.6769 -0.4572 0)
			(unlocked yes)
			(layer "F.Fab")
			(hide yes)
			(effects
				(font
					(size 1.016 1.016)
					(thickness 0.1524)
				)
			)
		)
		(property "Device Type" "L102078-254224H296"
			(at -5.6769 -1.9812 0)
			(unlocked yes)
			(layer "F.Fab")
			(hide yes)
			(effects
				(font
					(size 1.016 1.016)
					(thickness 0.1524)
				)
			)
		)
		(duplicate_pad_numbers_are_jumpers no)
		(fp_line
			(start -4.1529 -5.9944)
			(end -4.1529 5.9944)
			(stroke
				(width 0.1524)
				(type default)
			)
			(layer "F.SilkS")
		)
		(fp_line
			(start -4.1529 5.9944)
			(end 4.1529 5.9944)
			(stroke
				(width 0.1524)
				(type default)
			)
			(layer "F.SilkS")
		)
		(fp_line
			(start 4.1529 -5.9944)
			(end -4.1529 -5.9944)
			(stroke
				(width 0.1524)
				(type default)
			)
			(layer "F.SilkS")
		)
		(fp_line
			(start 4.1529 5.9944)
			(end 4.1529 -5.9944)
			(stroke
				(width 0.1524)
				(type default)
			)
			(layer "F.SilkS")
		)
		(fp_poly
			(pts
				(xy -3.8989 -5.1054) (xy -3.8989 5.1054) (xy 3.8989 5.1054) (xy 3.8989 -5.1054)
			)
			(stroke
				(width 0)
				(type default)
			)
			(fill no)
			(layer "F.CrtYd")
		)
		(fp_poly
			(pts
				(xy -3.8989 -5.1054) (xy 4.4069 -5.1054) (xy 4.4069 -6.0706) (xy -4.4069 -6.0706) (xy -4.4069 6.0706)
				(xy 4.4069 6.0706) (xy 4.4069 -5.0927) (xy 3.8989 -5.0927) (xy 3.8989 5.1054) (xy -3.8989 5.1054)
			)
			(stroke
				(width 0)
				(type default)
			)
			(fill no)
			(layer "F.CrtYd")
		)
		(fp_rect
			(start -4.4069 6.0706)
			(end 4.4069 -6.0706)
			(stroke
				(width 0)
				(type default)
			)
			(fill no)
			(layer "F.Fab")
		)
		(pad "1" smd rect
			(at 0 -4.020566)
			(size 2.4892 3.429)
			(layers "F.Cu" "F.Mask" "F.Paste")
			(net "P0V9_E_LX")
		)
		(pad "2" smd rect
			(at 0 4.020566)
			(size 2.4892 3.429)
			(layers "F.Cu" "F.Mask" "F.Paste")
			(net "P0V9_E")
		)
	)
	(footprint ""
		(layer "F.Cu")
		(at 77.47 -22.733 180)
		(property "Reference" "PR189"
			(at 0 0 180)
			(layer "F.SilkS")
			(hide yes)
			(effects
				(font
					(size 1.27 1.27)
				)
			)
		)
		(property "Value" "10KR2F-2-GP"
			(at 0.064008 -3.993896 180)
			(unlocked yes)
			(layer "F.Fab")
			(hide yes)
			(effects
				(font
					(size 1.016 1.016)
					(thickness 0.1524)
				)
			)
		)
		(property "Device Type" "R402H16"
			(at 0.064008 -5.517896 180)
			(unlocked yes)
			(layer "F.Fab")
			(hide yes)
			(effects
				(font
					(size 1.016 1.016)
					(thickness 0.1524)
				)
			)
		)
		(duplicate_pad_numbers_are_jumpers no)
		(fp_line
			(start 0.508 -0.9398)
			(end -0.508 -0.9398)
			(stroke
				(width 0.1524)
				(type default)
			)
			(layer "F.SilkS")
		)
		(fp_line
			(start -0.508 -0.9398)
			(end -0.508 0.9398)
			(stroke
				(width 0.1524)
				(type default)
			)
			(layer "F.SilkS")
		)
		(fp_rect
			(start -0.508 0.9398)
			(end 0.508 -0.9398)
			(stroke
				(width 0)
				(type default)
			)
			(fill no)
			(layer "F.CrtYd")
		)
		(fp_rect
			(start -0.508 0.9398)
			(end 0.508 -0.9398)
			(stroke
				(width 0)
				(type default)
			)
			(fill no)
			(layer "F.Fab")
		)
		(pad "1" smd custom
			(at 0 -0.4445 180)
			(size 0.1397 0.1397)
			(layers "F.Cu" "F.Mask" "F.Paste")
			(net "VT235_EN")
			(options
				(clearance outline)
				(anchor circle)
			)
			(primitives
				(gr_poly
					(pts
						(arc
							(start -0.1778 -0.2794)
							(mid -0.249642 -0.249642)
							(end -0.2794 -0.1778)
						)
						(arc
							(start -0.2794 0.1778)
							(mid -0.249642 0.249642)
							(end -0.1778 0.2794)
						)
						(arc
							(start 0.1778 0.2794)
							(mid 0.249642 0.249642)
							(end 0.2794 0.1778)
						)
						(arc
							(start 0.2794 -0.1778)
							(mid 0.249642 -0.249642)
							(end 0.1778 -0.2794)
						)
					)
					(width 0)
					(fill yes)
				)
			)
		)
		(pad "2" smd custom
			(at 0 0.4445 180)
			(size 0.1397 0.1397)
			(layers "F.Cu" "F.Mask" "F.Paste")
			(net "P3V3")
			(options
				(clearance outline)
				(anchor circle)
			)
			(primitives
				(gr_poly
					(pts
						(arc
							(start -0.1778 -0.2794)
							(mid -0.249642 -0.249642)
							(end -0.2794 -0.1778)
						)
						(arc
							(start -0.2794 0.1778)
							(mid -0.249642 0.249642)
							(end -0.1778 0.2794)
						)
						(arc
							(start 0.1778 0.2794)
							(mid 0.249642 0.249642)
							(end 0.2794 0.1778)
						)
						(arc
							(start 0.2794 -0.1778)
							(mid 0.249642 -0.249642)
							(end 0.1778 -0.2794)
						)
					)
					(width 0)
					(fill yes)
				)
			)
		)
	)
)
